(kicad_pcb
	(version 20260206)
	(generator "pcbnew")
	(generator_version "10.0")
	(general
		(thickness 1.6)
		(legacy_teardrops no)
	)
	(paper "A4")
	(title_block
		(title "timecard-production-celestica-r4006 — R4006-B0001-02_R01.brd")
		(comment 1 "Time Appliance Project (Time Card) / footprints 7-13 of 1113")
	)
	(layers
		(0 "F.Cu" signal "TOP")
		(4 "In1.Cu" signal "L02_GND1")
		(6 "In2.Cu" signal "L03_SIG1")
		(8 "In3.Cu" signal "L04_GND2")
		(10 "In4.Cu" signal "L05_VCC1")
		(12 "In5.Cu" signal "L06_VCC2")
		(14 "In6.Cu" signal "L07_GND3")
		(16 "In7.Cu" signal "L08_SIG2")
		(18 "In8.Cu" signal "L09_GND4")
		(2 "B.Cu" signal "BOTTOM")
		(9 "F.Adhes" user "F.Adhesive")
		(11 "B.Adhes" user "B.Adhesive")
		(13 "F.Paste" user "Package Geometry/Pastemask Top")
		(15 "B.Paste" user "Package Geometry/Pastemask Bottom")
		(5 "F.SilkS" user "Ref Des/Silkscreen Top")
		(7 "B.SilkS" user "Ref Des/Silkscreen Bottom")
		(1 "F.Mask" user "Board Geometry/Soldermask Top")
		(3 "B.Mask" user "Board Geometry/Soldermask Bottom")
		(17 "Dwgs.User" user "User.Drawings")
		(19 "Cmts.User" user "User.Comments")
		(21 "Eco1.User" user "User.Eco1")
		(23 "Eco2.User" user "User.Eco2")
		(25 "Edge.Cuts" user "Board Geometry/Outline")
		(27 "Margin" user)
		(31 "F.CrtYd" user "Package Geometry/Place Bound Top")
		(29 "B.CrtYd" user "Package Geometry/Place Bound Bottom")
		(35 "F.Fab" user "Ref Des/Assembly Top")
		(33 "B.Fab" user "Ref Des/Assembly Bottom")
	)
	(footprint ""
		(layer "F.Cu")
		(at 11.4808 -59.6138 -90)
		(property "Reference" "R498"
			(at -0.5842 1.40843 90)
			(unlocked yes)
			(layer "F.SilkS")
			(effects
				(font
					(size 0.7874 0.5842)
					(thickness 0.1524)
				)
			)
		)
		(property "Value" "VAL*"
			(at 0.02032 2.13233 270)
			(unlocked yes)
			(layer "F.Fab")
			(hide yes)
			(effects
				(font
					(size 0.7874 0.5842)
					(thickness 0.1524)
				)
			)
		)
		(property "Tolerance" "TOL*"
			(at 0.044704 3.05435 270)
			(unlocked yes)
			(layer "Cmts.User")
			(hide yes)
			(effects
				(font
					(size 0.7874 0.5842)
					(thickness 0.1524)
				)
			)
		)
		(property "User Part Number" "PARTNUM*"
			(at 0.02032 4.024884 270)
			(unlocked yes)
			(layer "Cmts.User")
			(hide yes)
			(effects
				(font
					(size 0.7874 0.5842)
					(thickness 0.1524)
				)
			)
		)
		(property "Device Type" "RESISTOR-G155-11004-01,1MOHM,1%"
			(at 0.008382 1.210564 270)
			(unlocked yes)
			(layer "F.Fab")
			(hide yes)
			(effects
				(font
					(size 0.7874 0.5842)
					(thickness 0.1524)
				)
			)
		)
		(duplicate_pad_numbers_are_jumpers no)
		(fp_line
			(start -1.143 0.5588)
			(end 1.143 0.5588)
			(stroke
				(width 0.1)
				(type default)
			)
			(layer "F.SilkS")
		)
		(fp_line
			(start 1.143 0.5588)
			(end 1.143 -0.5588)
			(stroke
				(width 0.1)
				(type default)
			)
			(layer "F.SilkS")
		)
		(fp_line
			(start -1.143 -0.5588)
			(end -1.143 0.5588)
			(stroke
				(width 0.1)
				(type default)
			)
			(layer "F.SilkS")
		)
		(fp_line
			(start 1.143 -0.5588)
			(end -1.143 -0.5588)
			(stroke
				(width 0.1)
				(type default)
			)
			(layer "F.SilkS")
		)
		(fp_poly
			(pts
				(xy -1.143 0.5588) (xy 1.143 0.5588) (xy 1.143 -0.5588) (xy -1.143 -0.5588)
			)
			(stroke
				(width 0)
				(type default)
			)
			(fill no)
			(layer "F.CrtYd")
		)
		(fp_line
			(start -0.508 0.3048)
			(end 0.508 0.3048)
			(stroke
				(width 0.1)
				(type default)
			)
			(layer "F.Fab")
		)
		(fp_line
			(start 0.508 0.3048)
			(end 0.508 -0.3048)
			(stroke
				(width 0.1)
				(type default)
			)
			(layer "F.Fab")
		)
		(fp_line
			(start -0.508 -0.3048)
			(end -0.508 0.3048)
			(stroke
				(width 0.1)
				(type default)
			)
			(layer "F.Fab")
		)
		(fp_line
			(start 0.508 -0.3048)
			(end -0.508 -0.3048)
			(stroke
				(width 0.1)
				(type default)
			)
			(layer "F.Fab")
		)
		(pad "1" smd rect
			(at -0.5334 0 270)
			(size 0.7112 0.6096)
			(layers "F.Cu" "F.Mask" "F.Paste")
			(net "SG")
		)
		(pad "2" smd rect
			(at 0.5334 0 270)
			(size 0.7112 0.6096)
			(layers "F.Cu" "F.Mask" "F.Paste")
			(net "BF_SMA1_SIG_IO_CONN")
		)
		(zone
			(layer "F.Cu")
			(hatch none 0.5)
			(connect_pads
				(clearance 0)
			)
			(min_thickness 0.25)
			(keepout
				(tracks allowed)
				(vias not_allowed)
				(pads allowed)
				(copperpour not_allowed)
				(footprints allowed)
			)
			(placement
				(enabled no)
				(sheetname "")
			)
			(fill
				(thermal_gap 0.5)
				(thermal_bridge_width 0.5)
				(island_removal_mode 0)
			)
			(polygon
				(pts
					(xy 11.176 -59.69) (xy 11.176 -59.5376) (xy 11.7856 -59.5376) (xy 11.7856 -59.69)
				)
			)
		)
		(zone
			(layer "F.Cu")
			(hatch none 0.5)
			(connect_pads
				(clearance 0)
			)
			(min_thickness 0.25)
			(keepout
				(tracks not_allowed)
				(vias allowed)
				(pads allowed)
				(copperpour not_allowed)
				(footprints allowed)
			)
			(placement
				(enabled no)
				(sheetname "")
			)
			(fill
				(thermal_gap 0.5)
				(thermal_bridge_width 0.5)
				(island_removal_mode 0)
			)
			(polygon
				(pts
					(xy 11.176 -59.69) (xy 11.176 -59.5376) (xy 11.7856 -59.5376) (xy 11.7856 -59.69)
				)
			)
		)
	)
	(footprint ""
		(layer "F.Cu")
		(at 135.763 -64.4144 180)
		(property "Reference" "TP56"
			(at -1.30175 -0.3048 90)
			(unlocked yes)
			(layer "F.SilkS")
			(effects
				(font
					(size 0.635 0.4064)
					(thickness 0.1524)
				)
				(justify left)
			)
		)
		(property "Value" ""
			(at 0 0 180)
			(layer "F.Fab")
			(effects
				(font
					(size 1.27 1.27)
				)
			)
		)
		(property "Device Type" "TP_PIONT-TP010CT020B030_PTH-TPA"
			(at -1.341882 0.996696 180)
			(unlocked yes)
			(layer "F.Fab")
			(hide yes)
			(effects
				(font
					(size 0.7874 0.5842)
					(thickness 0.1524)
				)
				(justify left)
			)
		)
		(duplicate_pad_numbers_are_jumpers no)
		(fp_poly
			(pts
				(arc
					(start -0.889 0)
					(mid 0.889 0)
					(end -0.889 0)
				)
			)
			(stroke
				(width 0)
				(type default)
			)
			(fill no)
			(layer "B.CrtYd")
		)
		(fp_poly
			(pts
				(arc
					(start -0.889 0)
					(mid 0.889 0)
					(end -0.889 0)
				)
			)
			(stroke
				(width 0)
				(type default)
			)
			(fill no)
			(layer "F.CrtYd")
		)
		(pad "1" thru_hole circle
			(at 0 0 180)
			(size 0.508 0.508)
			(drill 0.254)
			(layers "*.Cu" "*.Mask")
			(remove_unused_layers no)
			(net "XP1R8V_FPGA")
			(clearance 0.1016)
			(padstack
				(mode front_inner_back)
				(layer "Inner"
					(shape circle)
					(size 0.508 0.508)
					(clearance 0.1016)
				)
				(layer "B.Cu"
					(shape circle)
					(size 0.762 0.762)
					(clearance -0.0254)
				)
			)
		)
	)
	(footprint ""
		(layer "F.Cu")
		(at 134.62 -103.251)
		(property "Reference" "TP44"
			(at -3.8862 0.29337 0)
			(unlocked yes)
			(layer "F.SilkS")
			(effects
				(font
					(size 0.7874 0.5842)
					(thickness 0.1524)
				)
				(justify left)
			)
		)
		(property "Value" ""
			(at 0 0 0)
			(layer "F.Fab")
			(effects
				(font
					(size 1.27 1.27)
				)
			)
		)
		(property "Device Type" "TP_PIONT-TP010CT020B030_PTH-TPA"
			(at -1.341882 0.996696 0)
			(unlocked yes)
			(layer "F.Fab")
			(hide yes)
			(effects
				(font
					(size 0.7874 0.5842)
					(thickness 0.000001)
				)
				(justify left)
			)
		)
		(duplicate_pad_numbers_are_jumpers no)
		(fp_poly
			(pts
				(arc
					(start 0.889 0)
					(mid -0.889 0)
					(end 0.889 0)
				)
			)
			(stroke
				(width 0)
				(type default)
			)
			(fill no)
			(layer "B.CrtYd")
		)
		(fp_poly
			(pts
				(arc
					(start 0.889 0)
					(mid -0.889 0)
					(end 0.889 0)
				)
			)
			(stroke
				(width 0)
				(type default)
			)
			(fill no)
			(layer "F.CrtYd")
		)
		(pad "1" thru_hole circle
			(at 0 0)
			(size 0.508 0.508)
			(drill 0.254)
			(layers "*.Cu" "*.Mask")
			(remove_unused_layers no)
			(net "FPGA_DONE")
			(clearance 0.1016)
			(padstack
				(mode front_inner_back)
				(layer "Inner"
					(shape circle)
					(size 0.508 0.508)
					(clearance 0.1016)
				)
				(layer "B.Cu"
					(shape circle)
					(size 0.762 0.762)
					(clearance -0.0254)
				)
			)
		)
	)
	(footprint ""
		(layer "F.Cu")
		(at 48.26 -126.238)
		(property "Reference" "SP25"
			(at 0 0 0)
			(layer "F.SilkS")
			(hide yes)
			(effects
				(font
					(size 1.27 1.27)
				)
			)
		)
		(property "Value" ""
			(at 0 0 0)
			(layer "F.Fab")
			(effects
				(font
					(size 1.27 1.27)
				)
			)
		)
		(duplicate_pad_numbers_are_jumpers no)
	)
	(footprint ""
		(layer "F.Cu")
		(at 144.78 -54.102 -90)
		(property "Reference" "C262"
			(at 1.524 -3.08737 90)
			(unlocked yes)
			(layer "F.SilkS")
			(effects
				(font
					(size 0.7874 0.5842)
					(thickness 0.1524)
				)
			)
		)
		(property "Value" "VAL*"
			(at 0.0762 2.067306 270)
			(unlocked yes)
			(layer "F.Fab")
			(hide yes)
			(effects
				(font
					(size 0.7874 0.5842)
					(thickness 0.1524)
				)
			)
		)
		(property "Device Type" "CAPACITOR-G105-0B104-EK,0.1UF,A"
			(at 0.0508 1.127506 270)
			(unlocked yes)
			(layer "F.Fab")
			(hide yes)
			(effects
				(font
					(size 0.7874 0.5842)
					(thickness 0.1524)
				)
			)
		)
		(property "User Part Number" "PARTNUM*"
			(at 0.1016 4.023106 270)
			(unlocked yes)
			(layer "Cmts.User")
			(hide yes)
			(effects
				(font
					(size 0.7874 0.5842)
					(thickness 0.1524)
				)
			)
		)
		(property "Tolerance" "TOL*"
			(at 0.0762 3.032506 270)
			(unlocked yes)
			(layer "Cmts.User")
			(hide yes)
			(effects
				(font
					(size 0.7874 0.5842)
					(thickness 0.1524)
				)
			)
		)
		(duplicate_pad_numbers_are_jumpers no)
		(fp_line
			(start -1.143 0.5588)
			(end 1.143 0.5588)
			(stroke
				(width 0.1)
				(type default)
			)
			(layer "F.SilkS")
		)
		(fp_line
			(start 1.143 0.5588)
			(end 1.143 -0.5588)
			(stroke
				(width 0.1)
				(type default)
			)
			(layer "F.SilkS")
		)
		(fp_line
			(start -1.143 -0.5588)
			(end -1.143 0.5588)
			(stroke
				(width 0.1)
				(type default)
			)
			(layer "F.SilkS")
		)
		(fp_line
			(start 1.143 -0.5588)
			(end -1.143 -0.5588)
			(stroke
				(width 0.1)
				(type default)
			)
			(layer "F.SilkS")
		)
		(fp_rect
			(start 1.143 0.5588)
			(end -1.143 -0.5588)
			(stroke
				(width 0)
				(type default)
			)
			(fill no)
			(layer "F.CrtYd")
		)
		(fp_line
			(start -0.508 0.3048)
			(end 0.508 0.3048)
			(stroke
				(width 0.1)
				(type default)
			)
			(layer "F.Fab")
		)
		(fp_line
			(start 0.508 0.3048)
			(end 0.508 -0.3048)
			(stroke
				(width 0.1)
				(type default)
			)
			(layer "F.Fab")
		)
		(fp_line
			(start -0.508 -0.3048)
			(end -0.508 0.3048)
			(stroke
				(width 0.1)
				(type default)
			)
			(layer "F.Fab")
		)
		(fp_line
			(start 0.508 -0.3048)
			(end -0.508 -0.3048)
			(stroke
				(width 0.1)
				(type default)
			)
			(layer "F.Fab")
		)
		(pad "1" smd rect
			(at -0.5334 0 270)
			(size 0.7112 0.6096)
			(layers "F.Cu" "F.Mask" "F.Paste")
			(net "VIN_XP1R0V")
		)
		(pad "2" smd rect
			(at 0.5334 0 270)
			(size 0.7112 0.6096)
			(layers "F.Cu" "F.Mask" "F.Paste")
			(net "SG")
		)
		(zone
			(layer "F.Cu")
			(hatch none 0.5)
			(connect_pads
				(clearance 0)
			)
			(min_thickness 0.25)
			(keepout
				(tracks allowed)
				(vias not_allowed)
				(pads allowed)
				(copperpour not_allowed)
				(footprints allowed)
			)
			(placement
				(enabled no)
				(sheetname "")
			)
			(fill
				(thermal_gap 0.5)
				(thermal_bridge_width 0.5)
				(island_removal_mode 0)
			)
			(polygon
				(pts
					(xy 144.4752 -54.0258) (xy 145.0848 -54.0258) (xy 145.0848 -54.1782) (xy 144.4752 -54.1782)
				)
			)
		)
	)
	(footprint ""
		(layer "F.Cu")
		(at 162.56 -25.908 180)
		(property "Reference" "R414"
			(at -2.667 -0.80137 0)
			(unlocked yes)
			(layer "F.SilkS")
			(effects
				(font
					(size 0.7874 0.5842)
					(thickness 0.1524)
				)
			)
		)
		(property "Value" "VAL*"
			(at 0.02032 2.13233 180)
			(unlocked yes)
			(layer "F.Fab")
			(hide yes)
			(effects
				(font
					(size 0.7874 0.5842)
					(thickness 0.1524)
				)
			)
		)
		(property "Tolerance" "TOL*"
			(at 0.044704 3.05435 180)
			(unlocked yes)
			(layer "Cmts.User")
			(hide yes)
			(effects
				(font
					(size 0.7874 0.5842)
					(thickness 0.1524)
				)
			)
		)
		(property "User Part Number" "PARTNUM*"
			(at 0.02032 4.024884 180)
			(unlocked yes)
			(layer "Cmts.User")
			(hide yes)
			(effects
				(font
					(size 0.7874 0.5842)
					(thickness 0.1524)
				)
			)
		)
		(property "Device Type" "RESISTOR-G155-14701-01,4.7KOHMA"
			(at 0.008382 1.210564 180)
			(unlocked yes)
			(layer "F.Fab")
			(hide yes)
			(effects
				(font
					(size 0.7874 0.5842)
					(thickness 0.1524)
				)
			)
		)
		(duplicate_pad_numbers_are_jumpers no)
		(fp_line
			(start 1.143 0.5588)
			(end 1.143 -0.5588)
			(stroke
				(width 0.1)
				(type default)
			)
			(layer "F.SilkS")
		)
		(fp_line
			(start 1.143 -0.5588)
			(end -1.143 -0.5588)
			(stroke
				(width 0.1)
				(type default)
			)
			(layer "F.SilkS")
		)
		(fp_line
			(start -1.143 0.5588)
			(end 1.143 0.5588)
			(stroke
				(width 0.1)
				(type default)
			)
			(layer "F.SilkS")
		)
		(fp_line
			(start -1.143 -0.5588)
			(end -1.143 0.5588)
			(stroke
				(width 0.1)
				(type default)
			)
			(layer "F.SilkS")
		)
		(fp_rect
			(start 1.143 -0.5588)
			(end -1.143 0.5588)
			(stroke
				(width 0)
				(type default)
			)
			(fill no)
			(layer "F.CrtYd")
		)
		(fp_line
			(start 0.508 0.3048)
			(end 0.508 -0.3048)
			(stroke
				(width 0.1)
				(type default)
			)
			(layer "F.Fab")
		)
		(fp_line
			(start 0.508 -0.3048)
			(end -0.508 -0.3048)
			(stroke
				(width 0.1)
				(type default)
			)
			(layer "F.Fab")
		)
		(fp_line
			(start -0.508 0.3048)
			(end 0.508 0.3048)
			(stroke
				(width 0.1)
				(type default)
			)
			(layer "F.Fab")
		)
		(fp_line
			(start -0.508 -0.3048)
			(end -0.508 0.3048)
			(stroke
				(width 0.1)
				(type default)
			)
			(layer "F.Fab")
		)
		(pad "1" smd rect
			(at -0.5334 0 180)
			(size 0.7112 0.6096)
			(layers "F.Cu" "F.Mask" "F.Paste")
			(net "XP3R3V_FPGA")
		)
		(pad "2" smd rect
			(at 0.5334 0 180)
			(size 0.7112 0.6096)
			(layers "F.Cu" "F.Mask" "F.Paste")
			(net "UNNAMED_6_LM75BDPTSSOP8_I81_A1")
		)
		(zone
			(layer "F.Cu")
			(hatch none 0.5)
			(connect_pads
				(clearance 0)
			)
			(min_thickness 0.25)
			(keepout
				(tracks allowed)
				(vias not_allowed)
				(pads allowed)
				(copperpour not_allowed)
				(footprints allowed)
			)
			(placement
				(enabled no)
				(sheetname "")
			)
			(fill
				(thermal_gap 0.5)
				(thermal_bridge_width 0.5)
				(island_removal_mode 0)
			)
			(polygon
				(pts
					(xy 162.4838 -25.6032) (xy 162.6362 -25.6032) (xy 162.6362 -26.2128) (xy 162.4838 -26.2128)
				)
			)
		)
		(zone
			(layer "F.Cu")
			(hatch none 0.5)
			(connect_pads
				(clearance 0)
			)
			(min_thickness 0.25)
			(keepout
				(tracks not_allowed)
				(vias allowed)
				(pads allowed)
				(copperpour not_allowed)
				(footprints allowed)
			)
			(placement
				(enabled no)
				(sheetname "")
			)
			(fill
				(thermal_gap 0.5)
				(thermal_bridge_width 0.5)
				(island_removal_mode 0)
			)
			(polygon
				(pts
					(xy 162.4838 -25.6032) (xy 162.6362 -25.6032) (xy 162.6362 -26.2128) (xy 162.4838 -26.2128)
				)
			)
		)
	)
	(footprint ""
		(layer "F.Cu")
		(at 124.587 -50.165 180)
		(property "Reference" "R94"
			(at -0.127 -2.45237 0)
			(unlocked yes)
			(layer "F.SilkS")
			(effects
				(font
					(size 0.7874 0.5842)
					(thickness 0.1524)
				)
			)
		)
		(property "Value" "VAL*"
			(at 0.02032 2.13233 180)
			(unlocked yes)
			(layer "F.Fab")
			(hide yes)
			(effects
				(font
					(size 0.7874 0.5842)
					(thickness 0.1524)
				)
			)
		)
		(property "Device Type" "RESISTOR-G155-133R0-01,33OHM,1%"
			(at 0.008382 1.210564 180)
			(unlocked yes)
			(layer "F.Fab")
			(hide yes)
			(effects
				(font
					(size 0.7874 0.5842)
					(thickness 0.1524)
				)
			)
		)
		(property "User Part Number" "PARTNUM*"
			(at 0.02032 4.024884 180)
			(unlocked yes)
			(layer "Cmts.User")
			(hide yes)
			(effects
				(font
					(size 0.7874 0.5842)
					(thickness 0.1524)
				)
			)
		)
		(property "Tolerance" "TOL*"
			(at 0.044704 3.05435 180)
			(unlocked yes)
			(layer "Cmts.User")
			(hide yes)
			(effects
				(font
					(size 0.7874 0.5842)
					(thickness 0.1524)
				)
			)
		)
		(duplicate_pad_numbers_are_jumpers no)
		(fp_line
			(start 1.143 0.5588)
			(end 1.143 -0.5588)
			(stroke
				(width 0.1)
				(type default)
			)
			(layer "F.SilkS")
		)
		(fp_line
			(start 1.143 -0.5588)
			(end -1.143 -0.5588)
			(stroke
				(width 0.1)
				(type default)
			)
			(layer "F.SilkS")
		)
		(fp_line
			(start -1.143 0.5588)
			(end 1.143 0.5588)
			(stroke
				(width 0.1)
				(type default)
			)
			(layer "F.SilkS")
		)
		(fp_line
			(start -1.143 -0.5588)
			(end -1.143 0.5588)
			(stroke
				(width 0.1)
				(type default)
			)
			(layer "F.SilkS")
		)
		(fp_rect
			(start 1.143 -0.5588)
			(end -1.143 0.5588)
			(stroke
				(width 0)
				(type default)
			)
			(fill no)
			(layer "F.CrtYd")
		)
		(fp_line
			(start 0.508 0.3048)
			(end 0.508 -0.3048)
			(stroke
				(width 0.1)
				(type default)
			)
			(layer "F.Fab")
		)
		(fp_line
			(start 0.508 -0.3048)
			(end -0.508 -0.3048)
			(stroke
				(width 0.1)
				(type default)
			)
			(layer "F.Fab")
		)
		(fp_line
			(start -0.508 0.3048)
			(end 0.508 0.3048)
			(stroke
				(width 0.1)
				(type default)
			)
			(layer "F.Fab")
		)
		(fp_line
			(start -0.508 -0.3048)
			(end -0.508 0.3048)
			(stroke
				(width 0.1)
				(type default)
			)
			(layer "F.Fab")
		)
		(pad "1" smd rect
			(at -0.5334 0 180)
			(size 0.7112 0.6096)
			(layers "F.Cu" "F.Mask" "F.Paste")
			(net "R_MAC_UART_TX_FPGA_RX")
		)
		(pad "2" smd rect
			(at 0.5334 0 180)
			(size 0.7112 0.6096)
			(layers "F.Cu" "F.Mask" "F.Paste")
			(net "UART_MAC_TX_FPGA_RX")
		)
		(zone
			(layer "F.Cu")
			(hatch none 0.5)
			(connect_pads
				(clearance 0)
			)
			(min_thickness 0.25)
			(keepout
				(tracks allowed)
				(vias not_allowed)
				(pads allowed)
				(copperpour not_allowed)
				(footprints allowed)
			)
			(placement
				(enabled no)
				(sheetname "")
			)
			(fill
				(thermal_gap 0.5)
				(thermal_bridge_width 0.5)
				(island_removal_mode 0)
			)
			(polygon
				(pts
					(xy 124.5108 -49.8602) (xy 124.6632 -49.8602) (xy 124.6632 -50.4698) (xy 124.5108 -50.4698)
				)
			)
		)
	)
)
